# SCM (Grand Teton) — schematic netlist excerpt (pin names and nets, part order shuffled) for the footprints in the layout excerpt that follows; sources: Cadence DE-HDL packaged netlist, KiCad conversion of 12092022_DA0F0TMDCD0_F0T_Management_Board_D_brd_V3_OCP.brd

R12  Q_RES  4.7K 1% EMPTY  pkg 0402LF  page 26 : A = P3V3_AUX ; B = FRU_E0
L10  Q_INDUCTOR  BLM18PG121SN1D/2000MA IND  pkg SMLF  page 16 : \1\ = P1V8_AUX ; \2\ = P1V8_STBY_PE_VCC18A

(kicad_pcb
	(version 20260206)
	(generator "pcbnew")
	(generator_version "10.0")
	(general
		(thickness 1.6)
		(legacy_teardrops no)
	)
	(paper "A4")
	(title_block
		(title "12092022_DA0F0TMDCD0_F0T_Management_Board_D_brd_V3_OCP.brd")
		(comment 1 "Grand Teton / footprints 1000-1001 of 1440")
	)
	(layers
		(0 "F.Cu" signal "TOP")
		(4 "In1.Cu" signal "GND")
		(6 "In2.Cu" signal "IN1")
		(8 "In3.Cu" signal "GND1")
		(10 "In4.Cu" signal "IN2")
		(12 "In5.Cu" signal "VCC")
		(14 "In6.Cu" signal "VCC1")
		(16 "In7.Cu" signal "IN3")
		(18 "In8.Cu" signal "GND2")
		(20 "In9.Cu" signal "IN4")
		(22 "In10.Cu" signal "GND3")
		(2 "B.Cu" signal "BOTTOM")
		(9 "F.Adhes" user "F.Adhesive")
		(11 "B.Adhes" user "B.Adhesive")
		(13 "F.Paste" user "Package Geometry/Pastemask Top")
		(15 "B.Paste" user "Package Geometry/Pastemask Bottom")
		(5 "F.SilkS" user "Ref Des/Silkscreen Top")
		(7 "B.SilkS" user "Ref Des/Silkscreen Bottom")
		(1 "F.Mask" user "Board Geometry/Soldermask Top")
		(3 "B.Mask" user "Board Geometry/Soldermask Bottom")
		(17 "Dwgs.User" user "User.Drawings")
		(19 "Cmts.User" user "User.Comments")
		(21 "Eco1.User" user "User.Eco1")
		(23 "Eco2.User" user "User.Eco2")
		(25 "Edge.Cuts" user "Board Geometry/Outline")
		(27 "Margin" user)
		(31 "F.CrtYd" user "Package Geometry/Place Bound Top")
		(29 "B.CrtYd" user "Package Geometry/Place Bound Bottom")
		(35 "F.Fab" user "Ref Des/Assembly Top")
		(33 "B.Fab" user "Ref Des/Assembly Bottom")
	)
	(footprint ""
		(layer "B.Cu")
		(at 70.650862 -65.406016 90)
		(property "Reference" "L10"
			(at 0 0 90)
			(layer "B.SilkS")
			(hide yes)
			(effects
				(font
					(size 1.27 1.27)
				)
				(justify mirror)
			)
		)
		(property "Value" ""
			(at 0 0 90)
			(layer "B.Fab")
			(effects
				(font
					(size 1.27 1.27)
				)
				(justify mirror)
			)
		)
		(duplicate_pad_numbers_are_jumpers no)
		(fp_line
			(start 1.27 -0.5842)
			(end -1.27 -0.5842)
			(stroke
				(width 0.1524)
				(type default)
			)
			(layer "B.SilkS")
		)
		(fp_line
			(start 1.27 -0.5588)
			(end 1.27 -0.5842)
			(stroke
				(width 0.1524)
				(type default)
			)
			(layer "B.SilkS")
		)
		(fp_line
			(start 1.27 0.5842)
			(end 1.27 -0.5842)
			(stroke
				(width 0.1524)
				(type default)
			)
			(layer "B.SilkS")
		)
		(fp_line
			(start 0.127 0.5842)
			(end 0.127 -0.5842)
			(stroke
				(width 0.1524)
				(type default)
			)
			(layer "B.SilkS")
		)
		(fp_line
			(start -0.127 0.5842)
			(end -0.127 -0.5842)
			(stroke
				(width 0.1524)
				(type default)
			)
			(layer "B.SilkS")
		)
		(fp_line
			(start -1.27 0.5842)
			(end -1.27 -0.5842)
			(stroke
				(width 0.1524)
				(type default)
			)
			(layer "B.SilkS")
		)
		(fp_line
			(start -1.27 0.5842)
			(end 1.27 0.5842)
			(stroke
				(width 0.1524)
				(type default)
			)
			(layer "B.SilkS")
		)
		(fp_line
			(start 0.9144 -0.508)
			(end -0.9144 -0.508)
			(stroke
				(width 0.1)
				(type default)
			)
			(layer "B.Fab")
		)
		(fp_line
			(start -0.9144 -0.508)
			(end -0.9144 -0.406654)
			(stroke
				(width 0.1)
				(type default)
			)
			(layer "B.Fab")
		)
		(fp_line
			(start 1.194308 -0.406654)
			(end 0.9144 -0.406654)
			(stroke
				(width 0.1)
				(type default)
			)
			(layer "B.Fab")
		)
		(fp_line
			(start 0.9144 -0.406654)
			(end 0.9144 -0.508)
			(stroke
				(width 0.1)
				(type default)
			)
			(layer "B.Fab")
		)
		(fp_line
			(start -0.9144 -0.406654)
			(end -1.1938 -0.406654)
			(stroke
				(width 0.1)
				(type default)
			)
			(layer "B.Fab")
		)
		(fp_line
			(start -1.1938 -0.406654)
			(end -1.1938 0.4064)
			(stroke
				(width 0.1)
				(type default)
			)
			(layer "B.Fab")
		)
		(fp_line
			(start -0.9144 0.4064)
			(end -0.9144 0.508)
			(stroke
				(width 0.1)
				(type default)
			)
			(layer "B.Fab")
		)
		(fp_line
			(start -1.1938 0.4064)
			(end -0.9144 0.4064)
			(stroke
				(width 0.1)
				(type default)
			)
			(layer "B.Fab")
		)
		(fp_line
			(start 1.194308 0.406654)
			(end 1.194308 -0.406654)
			(stroke
				(width 0.1)
				(type default)
			)
			(layer "B.Fab")
		)
		(fp_line
			(start 0.9144 0.406654)
			(end 1.194308 0.406654)
			(stroke
				(width 0.1)
				(type default)
			)
			(layer "B.Fab")
		)
		(fp_line
			(start 0.9144 0.508)
			(end 0.9144 0.406654)
			(stroke
				(width 0.1)
				(type default)
			)
			(layer "B.Fab")
		)
		(fp_line
			(start -0.9144 0.508)
			(end 0.9144 0.508)
			(stroke
				(width 0.1)
				(type default)
			)
			(layer "B.Fab")
		)
		(pad "1" smd rect
			(at 0.7366 0)
			(size 0.7112 0.8128)
			(layers "B.Cu" "B.Mask" "B.Paste")
			(net "P1V8_AUX")
		)
		(pad "2" smd rect
			(at -0.7366 0)
			(size 0.7112 0.8128)
			(layers "B.Cu" "B.Mask" "B.Paste")
			(net "P1V8_STBY_PE_VCC18A")
		)
	)
	(footprint ""
		(layer "B.Cu")
		(at 85.32241 -28.627832)
		(property "Reference" "R12"
			(at 0 0 0)
			(layer "B.SilkS")
			(hide yes)
			(effects
				(font
					(size 1.27 1.27)
				)
				(justify mirror)
			)
		)
		(property "Value" ""
			(at 0 0 0)
			(layer "B.Fab")
			(effects
				(font
					(size 1.27 1.27)
				)
				(justify mirror)
			)
		)
		(duplicate_pad_numbers_are_jumpers no)
		(fp_line
			(start -0.7874 -0.4064)
			(end -0.7874 0.4064)
			(stroke
				(width 0.1524)
				(type default)
			)
			(layer "B.SilkS")
		)
		(fp_line
			(start -0.7874 0.4064)
			(end 0.7874 0.4064)
			(stroke
				(width 0.1524)
				(type default)
			)
			(layer "B.SilkS")
		)
		(fp_line
			(start 0.7874 -0.4064)
			(end -0.7874 -0.4064)
			(stroke
				(width 0.1524)
				(type default)
			)
			(layer "B.SilkS")
		)
		(fp_line
			(start 0.7874 0.4064)
			(end 0.7874 -0.4064)
			(stroke
				(width 0.1524)
				(type default)
			)
			(layer "B.SilkS")
		)
		(fp_line
			(start -0.67945 -0.3048)
			(end -0.67945 0.3048)
			(stroke
				(width 0.1)
				(type default)
			)
			(layer "B.Fab")
		)
		(fp_line
			(start -0.67945 0.3048)
			(end -0.120396 0.3048)
			(stroke
				(width 0.1)
				(type default)
			)
			(layer "B.Fab")
		)
		(fp_line
			(start -0.12065 -0.3048)
			(end -0.67945 -0.3048)
			(stroke
				(width 0.1)
				(type default)
			)
			(layer "B.Fab")
		)
		(fp_line
			(start -0.12065 -0.2794)
			(end -0.12065 -0.3048)
			(stroke
				(width 0.1)
				(type default)
			)
			(layer "B.Fab")
		)
		(fp_line
			(start -0.120396 0.2794)
			(end 0.12065 0.2794)
			(stroke
				(width 0.1)
				(type default)
			)
			(layer "B.Fab")
		)
		(fp_line
			(start -0.120396 0.3048)
			(end -0.120396 0.2794)
			(stroke
				(width 0.1)
				(type default)
			)
			(layer "B.Fab")
		)
		(fp_line
			(start 0.12065 -0.305054)
			(end 0.12065 -0.2794)
			(stroke
				(width 0.1)
				(type default)
			)
			(layer "B.Fab")
		)
		(fp_line
			(start 0.12065 -0.2794)
			(end -0.12065 -0.2794)
			(stroke
				(width 0.1)
				(type default)
			)
			(layer "B.Fab")
		)
		(fp_line
			(start 0.12065 0.2794)
			(end 0.12065 0.3048)
			(stroke
				(width 0.1)
				(type default)
			)
			(layer "B.Fab")
		)
		(fp_line
			(start 0.12065 0.3048)
			(end 0.67945 0.3048)
			(stroke
				(width 0.1)
				(type default)
			)
			(layer "B.Fab")
		)
		(fp_line
			(start 0.67945 -0.305054)
			(end 0.12065 -0.305054)
			(stroke
				(width 0.1)
				(type default)
			)
			(layer "B.Fab")
		)
		(fp_line
			(start 0.67945 0.3048)
			(end 0.67945 -0.305054)
			(stroke
				(width 0.1)
				(type default)
			)
			(layer "B.Fab")
		)
		(pad "1" smd circle
			(at 0.40005 0 180)
			(size 0 0)
			(layers "B.Cu" "B.Mask" "B.Paste")
			(net "P3V3_AUX")
		)
		(pad "2" smd circle
			(at -0.40005 0 180)
			(size 0 0)
			(layers "B.Cu" "B.Mask" "B.Paste")
			(net "FRU_E0")
		)
	)
)
